# T6G (Grand Teton) — schematic parts with pin connectivity, parts 8082–8082 of 8303; source: Cadence DE-HDL packaged netlist (pstxprt.dat, pstxnet.dat, pstchip.dat)

U26  GENOA_SP5  SOCKET6096_13568-001 IO  pkg SOCKET6096_93-4X120-45XA  page 37  (pins 337-672 of 6096)
  AD67  MFA_DATA26  BI  = M_F_CPU1_SA_DQ<26>
  AD68  VSS_AD68  POWER  = GND
  AD69  MEA_DATA25  BI  = M_E_CPU1_SA_DQ<25>
  AD70  MEA_DATA26  BI  = M_E_CPU1_SA_DQ<26>
  AD71  VSS_AD71  POWER  = GND
  AD72  MAA_DATA25  BI  = M_A_CPU1_SA_DQ<25>
  AD73  VSS_AD73  POWER  = GND
  AD74  MAA_DATA26  BI  = M_A_CPU1_SA_DQ<26>
  AE1  VSS_AE1  POWER  = GND
  AE2  MGA_DQS_H3  BI  = M_G_CPU1_SA_DQS_DP<3>
  AE3  MGA_DATA27  BI  = M_G_CPU1_SA_DQ<27>
  AE4  VSS_AE4  POWER  = GND
  AE5  MKA_DQS_H3  BI  = M_K_CPU1_SA_DQS_DP<3>
  AE6  VSS_AE6  POWER  = GND
  AE7  MKA_DATA27  BI  = M_K_CPU1_SA_DQ<27>
  AE8  VSS_AE8  POWER  = GND
  AE9  MLA_DQS_H3  BI  = M_L_CPU1_SA_DQS_DP<3>
  AE10  MLA_DATA27  BI  = M_L_CPU1_SA_DQ<27>
  AE11  VSS_AE11  POWER  = GND
  AE12  MHA_DQS_H3  BI  = M_H_CPU1_SA_DQS_DP<3>
  AE13  VSS_AE13  POWER  = GND
  AE14  MHA_DATA27  BI  = M_H_CPU1_SA_DQ<27>
  AE15  VSS_AE15  POWER  = GND
  AE16  MJA_DQS_H3  BI  = M_J_CPU1_SA_DQS_DP<3>
  AE17  MJA_DATA27  BI  = M_J_CPU1_SA_DQ<27>
  AE18  VSS_AE18  POWER  = GND
  AE19  MIA_DQS_H3  BI  = M_I_CPU1_SA_DQS_DP<3>
  AE20  VSS_AE20  POWER  = GND
  AE21  MIA_DATA27  BI  = M_I_CPU1_SA_DQ<27>
  AE22  VSS_AE22  POWER  = GND
  AE23  G2_RXN0  IN  = GMI_CPU0_G0_CPU1_G2_TX_DN<15>
  AE24  G2_RXP0  IN  = GMI_CPU0_G0_CPU1_G2_TX_DP<15>
  AE25  VSS_AE25  POWER  = GND
  AE26  G2_RXN3  IN  = GMI_CPU0_G0_CPU1_G2_TX_DN<12>
  AE27  G2_RXP3  IN  = GMI_CPU0_G0_CPU1_G2_TX_DP<12>
  AE28  VSS_AE28  POWER  = GND
  AE29  G2_RXN6  IN  = GMI_CPU0_G0_CPU1_G2_TX_DN<9>
  AE30  G2_RXP6  IN  = GMI_CPU0_G0_CPU1_G2_TX_DP<9>
  AE31  VSS_AE31  POWER  = GND
  AE32  G2_RXN9  IN  = GMI_CPU0_G0_CPU1_G2_TX_DN<6>
  AE33  G2_RXP9  IN  = GMI_CPU0_G0_CPU1_G2_TX_DP<6>
  AE34  VSS_AE34  POWER  = GND
  AE35  VSS_AE35  POWER  = GND
  AE36  VSS_AE36  POWER  = GND
  AE40  VSS_AE40  POWER  = GND
  AE41  VSS_AE41  POWER  = GND
  AE42  VSS_AE42  POWER  = GND
  AE43  G0_TXP6  OUT  = GMI_CPU1_G0_CPU0_G2_TX_DP<9>
  AE44  G0_TXN6  OUT  = GMI_CPU1_G0_CPU0_G2_TX_DN<9>
  AE45  VSS_AE45  POWER  = GND
  AE46  G0_TXP9  OUT  = GMI_CPU1_G0_CPU0_G2_TX_DP<6>
  AE47  G0_TXN9  OUT  = GMI_CPU1_G0_CPU0_G2_TX_DN<6>
  AE48  VSS_AE48  POWER  = GND
  AE49  G0_TXP12  OUT  = GMI_CPU1_G0_CPU0_G2_TX_DP<3>
  AE50  G0_TXN12  OUT  = GMI_CPU1_G0_CPU0_G2_TX_DN<3>
  AE51  VSS_AE51  POWER  = GND
  AE52  G0_TXP15  OUT  = GMI_CPU1_G0_CPU0_G2_TX_DP<0>
  AE53  G0_TXN15  OUT  = GMI_CPU1_G0_CPU0_G2_TX_DN<0>
  AE54  VSS_AE54  POWER  = GND
  AE55  MCA_DATA27  BI  = M_C_CPU1_SA_DQ<27>
  AE56  VSS_AE56  POWER  = GND
  AE57  MCA_DQS_H3  BI  = M_C_CPU1_SA_DQS_DP<3>
  AE58  VSS_AE58  POWER  = GND
  AE59  MDA_DATA27  BI  = M_D_CPU1_SA_DQ<27>
  AE60  MDA_DQS_H3  BI  = M_D_CPU1_SA_DQS_DP<3>
  AE61  VSS_AE61  POWER  = GND
  AE62  MBA_DATA27  BI  = M_B_CPU1_SA_DQ<27>
  AE63  VSS_AE63  POWER  = GND
  AE64  MBA_DQS_H3  BI  = M_B_CPU1_SA_DQS_DP<3>
  AE65  VSS_AE65  POWER  = GND
  AE66  MFA_DATA27  BI  = M_F_CPU1_SA_DQ<27>
  AE67  MFA_DQS_H3  BI  = M_F_CPU1_SA_DQS_DP<3>
  AE68  VSS_AE68  POWER  = GND
  AE69  MEA_DATA27  BI  = M_E_CPU1_SA_DQ<27>
  AE70  VSS_AE70  POWER  = GND
  AE71  MEA_DQS_H3  BI  = M_E_CPU1_SA_DQS_DP<3>
  AE72  VSS_AE72  POWER  = GND
  AE73  MAA_DATA27  BI  = M_A_CPU1_SA_DQ<27>
  AE74  MAA_DQS_H3  BI  = M_A_CPU1_SA_DQS_DP<3>
  AE75  VSS_AE75  POWER  = GND
  AF2  MGA_DQS_L3  BI  = M_G_CPU1_SA_DQS_DN<3>
  AF3  VSS_AF3  POWER  = GND
  AF4  MGA_DQS_L8  BI  = M_G_CPU1_SA_DQS_DN<8>
  AF5  VDDCR_SOC_AF5  POWER  = PVDDCR_SOC_P1
  AF6  MKA_DQS_L3  BI  = M_K_CPU1_SA_DQS_DN<3>
  AF7  MKA_DQS_L8  BI  = M_K_CPU1_SA_DQS_DN<8>
  AF8  VSS_AF8  POWER  = GND
  AF9  MLA_DQS_L3  BI  = M_L_CPU1_SA_DQS_DN<3>
  AF10  VSS_AF10  POWER  = GND
  AF11  MLA_DQS_L8  BI  = M_L_CPU1_SA_DQS_DN<8>
  AF12  VDDCR_SOC_AF12  POWER  = PVDDCR_SOC_P1
  AF13  MHA_DQS_L3  BI  = M_H_CPU1_SA_DQS_DN<3>
  AF14  MHA_DQS_L8  BI  = M_H_CPU1_SA_DQS_DN<8>
  AF15  VSS_AF15  POWER  = GND
  AF16  MJA_DQS_L3  BI  = M_J_CPU1_SA_DQS_DN<3>
  AF17  VSS_AF17  POWER  = GND
  AF18  MJA_DQS_L8  BI  = M_J_CPU1_SA_DQS_DN<8>
  AF19  VDDCR_SOC_AF19  POWER  = PVDDCR_SOC_P1
  AF20  MIA_DQS_L3  BI  = M_I_CPU1_SA_DQS_DN<3>
  AF21  MIA_DQS_L8  BI  = M_I_CPU1_SA_DQS_DN<8>
  AF22  VSS_AF22  POWER  = GND
  AF23  VDDCR_CPU0_AF23  POWER  = PVDDCR_CPU0_P1
  AF24  VDDCR_CPU0_AF24  POWER  = PVDDCR_CPU0_P1
  AF25  VSS_AF25  POWER  = GND
  AF26  VDDCR_CPU0_AF26  POWER  = PVDDCR_CPU0_P1
  AF27  VDDCR_CPU0_AF27  POWER  = PVDDCR_CPU0_P1
  AF28  VSS_AF28  POWER  = GND
  AF29  VDDCR_CPU0_AF29  POWER  = PVDDCR_CPU0_P1
  AF30  VDDCR_CPU0_AF30  POWER  = PVDDCR_CPU0_P1
  AF31  VSS_AF31  POWER  = GND
  AF32  VDDCR_CPU0_AF32  POWER  = PVDDCR_CPU0_P1
  AF33  VDDCR_CPU0_AF33  POWER  = PVDDCR_CPU0_P1
  AF34  VSS_AF34  POWER  = GND
  AF35  G2_RXN15  IN  = GMI_CPU0_G0_CPU1_G2_TX_DN<0>
  AF36  G2_RXP15  IN  = GMI_CPU0_G0_CPU1_G2_TX_DP<0>
  AF37  VSS_AF37  POWER  = GND
  AF39  VSS_AF39  POWER  = GND
  AF40  G0_TXP0  OUT  = GMI_CPU1_G0_CPU0_G2_TX_DP<15>
  AF41  G0_TXN0  OUT  = GMI_CPU1_G0_CPU0_G2_TX_DN<15>
  AF42  VSS_AF42  POWER  = GND
  AF43  VDDCR_CPU0_AF43  POWER  = PVDDCR_CPU0_P1
  AF44  VDDCR_CPU0_AF44  POWER  = PVDDCR_CPU0_P1
  AF45  VSS_AF45  POWER  = GND
  AF46  VDDCR_CPU0_AF46  POWER  = PVDDCR_CPU0_P1
  AF47  VDDCR_CPU0_AF47  POWER  = PVDDCR_CPU0_P1
  AF48  VSS_AF48  POWER  = GND
  AF49  VDDCR_CPU0_AF49  POWER  = PVDDCR_CPU0_P1
  AF50  VDDCR_CPU0_AF50  POWER  = PVDDCR_CPU0_P1
  AF51  VSS_AF51  POWER  = GND
  AF52  VDDCR_CPU0_AF52  POWER  = PVDDCR_CPU0_P1
  AF53  VDDCR_CPU0_AF53  POWER  = PVDDCR_CPU0_P1
  AF54  VSS_AF54  POWER  = GND
  AF55  MCA_DQS_L8  BI  = M_C_CPU1_SA_DQS_DN<8>
  AF56  MCA_DQS_L3  BI  = M_C_CPU1_SA_DQS_DN<3>
  AF57  VDDIO_AF57  POWER  = PVDDIO_P1
  AF58  MDA_DQS_L8  BI  = M_D_CPU1_SA_DQS_DN<8>
  AF59  VSS_AF59  POWER  = GND
  AF60  MDA_DQS_L3  BI  = M_D_CPU1_SA_DQS_DN<3>
  AF61  VSS_AF61  POWER  = GND
  AF62  MBA_DQS_L8  BI  = M_B_CPU1_SA_DQS_DN<8>
  AF63  MBA_DQS_L3  BI  = M_B_CPU1_SA_DQS_DN<3>
  AF64  VDDIO_AF64  POWER  = PVDDIO_P1
  AF65  MFA_DQS_L8  BI  = M_F_CPU1_SA_DQS_DN<8>
  AF66  VSS_AF66  POWER  = GND
  AF67  MFA_DQS_L3  BI  = M_F_CPU1_SA_DQS_DN<3>
  AF68  VSS_AF68  POWER  = GND
  AF69  MEA_DQS_L8  BI  = M_E_CPU1_SA_DQS_DN<8>
  AF70  MEA_DQS_L3  BI  = M_E_CPU1_SA_DQS_DN<3>
  AF71  VDDIO_AF71  POWER  = PVDDIO_P1
  AF72  MAA_DQS_L8  BI  = M_A_CPU1_SA_DQS_DN<8>
  AF73  VSS_AF73  POWER  = GND
  AF74  MAA_DQS_L3  BI  = M_A_CPU1_SA_DQS_DN<3>
  AG1  VSS_AG1  POWER  = GND
  AG2  MGA_DATA28  BI  = M_G_CPU1_SA_DQ<28>
  AG3  MGA_DQS_H8  BI  = M_G_CPU1_SA_DQS_DP<8>
  AG4  VSS_AG4  POWER  = GND
  AG5  MKA_DATA28  BI  = M_K_CPU1_SA_DQ<28>
  AG6  VSS_AG6  POWER  = GND
  AG7  MKA_DQS_H8  BI  = M_K_CPU1_SA_DQS_DP<8>
  AG8  VSS_AG8  POWER  = GND
  AG9  MLA_DATA28  BI  = M_L_CPU1_SA_DQ<28>
  AG10  MLA_DQS_H8  BI  = M_L_CPU1_SA_DQS_DP<8>
  AG11  VSS_AG11  POWER  = GND
  AG12  MHA_DATA28  BI  = M_H_CPU1_SA_DQ<28>
  AG13  VSS_AG13  POWER  = GND
  AG14  MHA_DQS_H8  BI  = M_H_CPU1_SA_DQS_DP<8>
  AG15  VSS_AG15  POWER  = GND
  AG16  MJA_DATA28  BI  = M_J_CPU1_SA_DQ<28>
  AG17  MJA_DQS_H8  BI  = M_J_CPU1_SA_DQS_DP<8>
  AG18  VSS_AG18  POWER  = GND
  AG19  MIA_DATA28  BI  = M_I_CPU1_SA_DQ<28>
  AG20  VSS_AG20  POWER  = GND
  AG21  MIA_DQS_H8  BI  = M_I_CPU1_SA_DQS_DP<8>
  AG22  VSS_AG22  POWER  = GND
  AG23  G2_RXN2  IN  = GMI_CPU0_G0_CPU1_G2_TX_DN<13>
  AG24  G2_RXP2  IN  = GMI_CPU0_G0_CPU1_G2_TX_DP<13>
  AG25  VSS_AG25  POWER  = GND
  AG26  G2_RXN5  IN  = GMI_CPU0_G0_CPU1_G2_TX_DN<10>
  AG27  G2_RXP5  IN  = GMI_CPU0_G0_CPU1_G2_TX_DP<10>
  AG28  VSS_AG28  POWER  = GND
  AG29  G2_RXN8  IN  = GMI_CPU0_G0_CPU1_G2_TX_DN<7>
  AG30  G2_RXP8  IN  = GMI_CPU0_G0_CPU1_G2_TX_DP<7>
  AG31  VSS_AG31  POWER  = GND
  AG32  G2_RXN12  IN  = GMI_CPU0_G0_CPU1_G2_TX_DN<3>
  AG33  G2_RXP12  IN  = GMI_CPU0_G0_CPU1_G2_TX_DP<3>
  AG34  VSS_AG34  POWER  = GND
  AG35  VDDCR_CPU0_AG35  POWER  = PVDDCR_CPU0_P1
  AG36  VDDCR_CPU0_AG36  POWER  = PVDDCR_CPU0_P1
  AG40  VDDCR_CPU0_AG40  POWER  = PVDDCR_CPU0_P1
  AG41  VDDCR_CPU0_AG41  POWER  = PVDDCR_CPU0_P1
  AG42  VSS_AG42  POWER  = GND
  AG43  G0_TXP3  OUT  = GMI_CPU1_G0_CPU0_G2_TX_DP<12>
  AG44  G0_TXN3  OUT  = GMI_CPU1_G0_CPU0_G2_TX_DN<12>
  AG45  VSS_AG45  POWER  = GND
  AG46  G0_TXP7  OUT  = GMI_CPU1_G0_CPU0_G2_TX_DP<8>
  AG47  G0_TXN7  OUT  = GMI_CPU1_G0_CPU0_G2_TX_DN<8>
  AG48  VSS_AG48  POWER  = GND
  AG49  G0_TXP10  OUT  = GMI_CPU1_G0_CPU0_G2_TX_DP<5>
  AG50  G0_TXN10  OUT  = GMI_CPU1_G0_CPU0_G2_TX_DN<5>
  AG51  VSS_AG51  POWER  = GND
  AG52  G0_TXP13  OUT  = GMI_CPU1_G0_CPU0_G2_TX_DP<2>
  AG53  G0_TXN13  OUT  = GMI_CPU1_G0_CPU0_G2_TX_DN<2>
  AG54  VSS_AG54  POWER  = GND
  AG55  MCA_DQS_H8  BI  = M_C_CPU1_SA_DQS_DP<8>
  AG56  VSS_AG56  POWER  = GND
  AG57  MCA_DATA28  BI  = M_C_CPU1_SA_DQ<28>
  AG58  VSS_AG58  POWER  = GND
  AG59  MDA_DQS_H8  BI  = M_D_CPU1_SA_DQS_DP<8>
  AG60  MDA_DATA28  BI  = M_D_CPU1_SA_DQ<28>
  AG61  VSS_AG61  POWER  = GND
  AG62  MBA_DQS_H8  BI  = M_B_CPU1_SA_DQS_DP<8>
  AG63  VSS_AG63  POWER  = GND
  AG64  MBA_DATA28  BI  = M_B_CPU1_SA_DQ<28>
  AG65  VSS_AG65  POWER  = GND
  AG66  MFA_DQS_H8  BI  = M_F_CPU1_SA_DQS_DP<8>
  AG67  MFA_DATA28  BI  = M_F_CPU1_SA_DQ<28>
  AG68  VSS_AG68  POWER  = GND
  AG69  MEA_DQS_H8  BI  = M_E_CPU1_SA_DQS_DP<8>
  AG70  VSS_AG70  POWER  = GND
  AG71  MEA_DATA28  BI  = M_E_CPU1_SA_DQ<28>
  AG72  VSS_AG72  POWER  = GND
  AG73  MAA_DQS_H8  BI  = M_A_CPU1_SA_DQS_DP<8>
  AG74  MAA_DATA28  BI  = M_A_CPU1_SA_DQ<28>
  AG75  VSS_AG75  POWER  = GND
  AH2  MGA_DATA30  BI  = M_G_CPU1_SA_DQ<30>
  AH3  VSS_AH3  POWER  = GND
  AH4  MGA_DATA29  BI  = M_G_CPU1_SA_DQ<29>
  AH5  VSS_AH5  POWER  = GND
  AH6  MKA_DATA30  BI  = M_K_CPU1_SA_DQ<30>
  AH7  MKA_DATA29  BI  = M_K_CPU1_SA_DQ<29>
  AH8  VSS_AH8  POWER  = GND
  AH9  MLA_DATA30  BI  = M_L_CPU1_SA_DQ<30>
  AH10  VSS_AH10  POWER  = GND
  AH11  MLA_DATA29  BI  = M_L_CPU1_SA_DQ<29>
  AH12  VSS_AH12  POWER  = GND
  AH13  MHA_DATA30  BI  = M_H_CPU1_SA_DQ<30>
  AH14  MHA_DATA29  BI  = M_H_CPU1_SA_DQ<29>
  AH15  VSS_AH15  POWER  = GND
  AH16  MJA_DATA30  BI  = M_J_CPU1_SA_DQ<30>
  AH17  VSS_AH17  POWER  = GND
  AH18  MJA_DATA29  BI  = M_J_CPU1_SA_DQ<29>
  AH19  VSS_AH19  POWER  = GND
  AH20  MIA_DATA30  BI  = M_I_CPU1_SA_DQ<30>
  AH21  MIA_DATA29  BI  = M_I_CPU1_SA_DQ<29>
  AH22  VDDCR_SOC_AH22  POWER  = PVDDCR_SOC_P1
  AH23  VSS_AH23  POWER  = GND
  AH24  VSS_AH24  POWER  = GND
  AH25  VSS_AH25  POWER  = GND
  AH26  VSS_AH26  POWER  = GND
  AH27  VSS_AH27  POWER  = GND
  AH28  VSS_AH28  POWER  = GND
  AH29  VSS_AH29  POWER  = GND
  AH30  VSS_AH30  POWER  = GND
  AH31  VSS_AH31  POWER  = GND
  AH32  VSS_AH32  POWER  = GND
  AH33  VSS_AH33  POWER  = GND
  AH34  VSS_AH34  POWER  = GND
  AH35  \g3_rxn13||sata35_rxn\  IN  = GMI_CPU0_G1_CPU1_G3_TX_DN<2>
  AH36  \g3_rxp13||sata35_rxp\  IN  = GMI_CPU0_G1_CPU1_G3_TX_DP<2>
  AH37  VSS_AH37  POWER  = GND
  AH39  VSS_AH39  POWER  = GND
  AH40  G1_TXP2  OUT  = P5E_CPU1_G1_TX_DP<2>
  AH41  G1_TXN2  OUT  = P5E_CPU1_G1_TX_DN<2>
  AH42  VSS_AH42  POWER  = GND
  AH43  VSS_AH43  POWER  = GND
  AH44  VSS_AH44  POWER  = GND
  AH45  VSS_AH45  POWER  = GND
  AH46  VSS_AH46  POWER  = GND
  AH47  VSS_AH47  POWER  = GND
  AH48  VSS_AH48  POWER  = GND
  AH49  VSS_AH49  POWER  = GND
  AH50  VSS_AH50  POWER  = GND
  AH51  VSS_AH51  POWER  = GND
  AH52  VSS_AH52  POWER  = GND
  AH53  VSS_AH53  POWER  = GND
  AH54  VDDIO_AH54  POWER  = PVDDIO_P1
  AH55  MCA_DATA29  BI  = M_C_CPU1_SA_DQ<29>
  AH56  MCA_DATA30  BI  = M_C_CPU1_SA_DQ<30>
  AH57  VSS_AH57  POWER  = GND
  AH58  MDA_DATA29  BI  = M_D_CPU1_SA_DQ<29>
  AH59  VSS_AH59  POWER  = GND
  AH60  MDA_DATA30  BI  = M_D_CPU1_SA_DQ<30>
  AH61  VSS_AH61  POWER  = GND
  AH62  MBA_DATA29  BI  = M_B_CPU1_SA_DQ<29>
  AH63  MBA_DATA30  BI  = M_B_CPU1_SA_DQ<30>
  AH64  VSS_AH64  POWER  = GND
  AH65  MFA_DATA29  BI  = M_F_CPU1_SA_DQ<29>
  AH66  VSS_AH66  POWER  = GND
  AH67  MFA_DATA30  BI  = M_F_CPU1_SA_DQ<30>
  AH68  VSS_AH68  POWER  = GND
  AH69  MEA_DATA29  BI  = M_E_CPU1_SA_DQ<29>
  AH70  MEA_DATA30  BI  = M_E_CPU1_SA_DQ<30>
  AH71  VSS_AH71  POWER  = GND
  AH72  MAA_DATA29  BI  = M_A_CPU1_SA_DQ<29>
  AH73  VSS_AH73  POWER  = GND
  AH74  MAA_DATA30  BI  = M_A_CPU1_SA_DQ<30>
  AJ1  VSS_AJ1  POWER  = GND
  AJ2  MGA_CHECK0  BI  = M_G_CPU1_SA_CB<0>
  AJ3  MGA_DATA31  BI  = M_G_CPU1_SA_DQ<31>
  AJ4  VDDCR_SOC_AJ4  POWER  = PVDDCR_SOC_P1
  AJ5  MKA_CHECK0  BI  = M_K_CPU1_SA_CB<0>
  AJ6  VSS_AJ6  POWER  = GND
  AJ7  MKA_DATA31  BI  = M_K_CPU1_SA_DQ<31>
  AJ8  VSS_AJ8  POWER  = GND
  AJ9  MLA_CHECK0  BI  = M_L_CPU1_SA_CB<0>
  AJ10  MLA_DATA31  BI  = M_L_CPU1_SA_DQ<31>
  AJ11  VDDCR_SOC_AJ11  POWER  = PVDDCR_SOC_P1
  AJ12  MHA_CHECK0  BI  = M_H_CPU1_SA_CB<0>
  AJ13  VSS_AJ13  POWER  = GND
  AJ14  MHA_DATA31  BI  = M_H_CPU1_SA_DQ<31>
  AJ15  VSS_AJ15  POWER  = GND
  AJ16  MJA_CHECK0  BI  = M_J_CPU1_SA_CB<0>
  AJ17  MJA_DATA31  BI  = M_J_CPU1_SA_DQ<31>
  AJ18  VDDCR_SOC_AJ18  POWER  = PVDDCR_SOC_P1
  AJ19  MIA_CHECK0  BI  = M_I_CPU1_SA_CB<0>
  AJ20  VSS_AJ20  POWER  = GND
  AJ21  MIA_DATA31  BI  = M_I_CPU1_SA_DQ<31>
  AJ22  VSS_AJ22  POWER  = GND
  AJ23  \g3_rxn1||sata21_rxn\  IN  = GMI_CPU0_G1_CPU1_G3_TX_DN<14>
  AJ24  \g3_rxp1||sata21_rxp\  IN  = GMI_CPU0_G1_CPU1_G3_TX_DP<14>
  AJ25  VSS_AJ25  POWER  = GND
  AJ26  \g3_rxn4||sata24_rxn\  IN  = GMI_CPU0_G1_CPU1_G3_TX_DN<11>
  AJ27  \g3_rxp4||sata24_rxp\  IN  = GMI_CPU0_G1_CPU1_G3_TX_DP<11>
  AJ28  VSS_AJ28  POWER  = GND
  AJ29  \g3_rxn7||sata27_rxn\  IN  = GMI_CPU0_G1_CPU1_G3_TX_DN<8>
  AJ30  \g3_rxp7||sata27_rxp\  IN  = GMI_CPU0_G1_CPU1_G3_TX_DP<8>
  AJ31  VSS_AJ31  POWER  = GND
  AJ32  \g3_rxn10||sata32_rxn\  IN  = GMI_CPU0_G1_CPU1_G3_TX_DN<5>
  AJ33  \g3_rxp10||sata32_rxp\  IN  = GMI_CPU0_G1_CPU1_G3_TX_DP<5>
  AJ34  VSS_AJ34  POWER  = GND
  AJ35  VSS_AJ35  POWER  = GND
  AJ36  VSS_AJ36  POWER  = GND
  AJ40  VSS_AJ40  POWER  = GND
  AJ41  VSS_AJ41  POWER  = GND
  AJ42  VSS_AJ42  POWER  = GND
  AJ43  G1_TXP5  OUT  = P5E_CPU1_G1_TX_DP<5>
